# T6G (Grand Teton) — schematic netlist excerpt (pin names and nets, part order shuffled) for the footprints in the layout excerpt that follows; sources: Cadence DE-HDL packaged netlist, KiCad conversion of 04192023_DAF0TMB3IC0_F0TG_MB_C_brd_V02_OCP.brd

R6312  Q_RES  10K 1% CHIP  pkg 0402LF  page 178 : A = P3V3_AUX ; B = USB_HUB2_TI_OVERCUR1
PR3963  Q_RES  25.5K 1% CHIP  pkg 0402LF  page 146 : A = P3V3_AUX ; B = P3V3_E1S_UV_0
C723  Q_CAP_DIFFBUS  DIFF BUS_0.22UF 6.3V 20% X6S  pkg C0201  page 66 : \1\ = P5E_CPU1_P1_TX_C_DP<9> ; \2\ = P5E_CPU1_P1_TX_DP<9>

(kicad_pcb
	(version 20260206)
	(generator "pcbnew")
	(generator_version "10.0")
	(general
		(thickness 1.6)
		(legacy_teardrops no)
	)
	(paper "A4")
	(title_block
		(title "04192023_DAF0TMB3IC0_F0TG_MB_C_brd_V02_OCP.brd")
		(comment 1 "Grand Teton / footprints 1294-1296 of 8354")
	)
	(layers
		(0 "F.Cu" signal "TOP")
		(4 "In1.Cu" signal "GND")
		(6 "In2.Cu" signal "IN1")
		(8 "In3.Cu" signal "GND1")
		(10 "In4.Cu" signal "IN2")
		(12 "In5.Cu" signal "GND2")
		(14 "In6.Cu" signal "IN3")
		(16 "In7.Cu" signal "GND3")
		(18 "In8.Cu" signal "VCC")
		(20 "In9.Cu" signal "VCC1")
		(22 "In10.Cu" signal "GND4")
		(24 "In11.Cu" signal "IN4")
		(26 "In12.Cu" signal "GND5")
		(28 "In13.Cu" signal "IN5")
		(30 "In14.Cu" signal "GND6")
		(32 "In15.Cu" signal "IN6")
		(34 "In16.Cu" signal "GND7")
		(2 "B.Cu" signal "BOTTOM")
		(9 "F.Adhes" user "F.Adhesive")
		(11 "B.Adhes" user "B.Adhesive")
		(13 "F.Paste" user "Package Geometry/Pastemask Top")
		(15 "B.Paste" user "Package Geometry/Pastemask Bottom")
		(5 "F.SilkS" user "Ref Des/Silkscreen Top")
		(7 "B.SilkS" user "Ref Des/Silkscreen Bottom")
		(1 "F.Mask" user "Board Geometry/Soldermask Top")
		(3 "B.Mask" user "Board Geometry/Soldermask Bottom")
		(17 "Dwgs.User" user "User.Drawings")
		(19 "Cmts.User" user "User.Comments")
		(21 "Eco1.User" user "User.Eco1")
		(23 "Eco2.User" user "User.Eco2")
		(25 "Edge.Cuts" user "Board Geometry/Outline")
		(27 "Margin" user)
		(31 "F.CrtYd" user "Package Geometry/Place Bound Top")
		(29 "B.CrtYd" user "Package Geometry/Place Bound Bottom")
		(35 "F.Fab" user "Ref Des/Assembly Top")
		(33 "B.Fab" user "Ref Des/Assembly Bottom")
	)
	(footprint ""
		(layer "F.Cu")
		(at 108.533946 -54.882034 -90)
		(property "Reference" "R6312"
			(at 0 0 270)
			(layer "F.SilkS")
			(hide yes)
			(effects
				(font
					(size 1.27 1.27)
				)
			)
		)
		(property "Value" ""
			(at 0 0 270)
			(layer "F.Fab")
			(effects
				(font
					(size 1.27 1.27)
				)
			)
		)
		(duplicate_pad_numbers_are_jumpers no)
		(fp_line
			(start -0.7874 0.4064)
			(end -0.7874 -0.4064)
			(stroke
				(width 0.1524)
				(type default)
			)
			(layer "F.SilkS")
		)
		(fp_line
			(start 0.7874 0.4064)
			(end -0.7874 0.4064)
			(stroke
				(width 0.1524)
				(type default)
			)
			(layer "F.SilkS")
		)
		(fp_line
			(start -0.7874 -0.4064)
			(end 0.7874 -0.4064)
			(stroke
				(width 0.1524)
				(type default)
			)
			(layer "F.SilkS")
		)
		(fp_line
			(start 0.7874 -0.4064)
			(end 0.7874 0.4064)
			(stroke
				(width 0.1524)
				(type default)
			)
			(layer "F.SilkS")
		)
		(fp_line
			(start -0.67945 0.3048)
			(end -0.67945 -0.305054)
			(stroke
				(width 0.1)
				(type default)
			)
			(layer "F.Fab")
		)
		(fp_line
			(start -0.12065 0.3048)
			(end -0.67945 0.3048)
			(stroke
				(width 0.1)
				(type default)
			)
			(layer "F.Fab")
		)
		(fp_line
			(start 0.120396 0.3048)
			(end 0.120396 0.2794)
			(stroke
				(width 0.1)
				(type default)
			)
			(layer "F.Fab")
		)
		(fp_line
			(start 0.67945 0.3048)
			(end 0.120396 0.3048)
			(stroke
				(width 0.1)
				(type default)
			)
			(layer "F.Fab")
		)
		(fp_line
			(start -0.12065 0.2794)
			(end -0.12065 0.3048)
			(stroke
				(width 0.1)
				(type default)
			)
			(layer "F.Fab")
		)
		(fp_line
			(start 0.120396 0.2794)
			(end -0.12065 0.2794)
			(stroke
				(width 0.1)
				(type default)
			)
			(layer "F.Fab")
		)
		(fp_line
			(start -0.12065 -0.2794)
			(end 0.12065 -0.2794)
			(stroke
				(width 0.1)
				(type default)
			)
			(layer "F.Fab")
		)
		(fp_line
			(start 0.12065 -0.2794)
			(end 0.12065 -0.3048)
			(stroke
				(width 0.1)
				(type default)
			)
			(layer "F.Fab")
		)
		(fp_line
			(start 0.12065 -0.3048)
			(end 0.67945 -0.3048)
			(stroke
				(width 0.1)
				(type default)
			)
			(layer "F.Fab")
		)
		(fp_line
			(start 0.67945 -0.3048)
			(end 0.67945 0.3048)
			(stroke
				(width 0.1)
				(type default)
			)
			(layer "F.Fab")
		)
		(fp_line
			(start -0.67945 -0.305054)
			(end -0.12065 -0.305054)
			(stroke
				(width 0.1)
				(type default)
			)
			(layer "F.Fab")
		)
		(fp_line
			(start -0.12065 -0.305054)
			(end -0.12065 -0.2794)
			(stroke
				(width 0.1)
				(type default)
			)
			(layer "F.Fab")
		)
		(pad "1" smd circle
			(at -0.40005 0 270)
			(size 0 0)
			(layers "F.Cu" "F.Mask" "F.Paste")
			(net "P3V3_AUX")
		)
		(pad "2" smd circle
			(at 0.40005 0 270)
			(size 0 0)
			(layers "F.Cu" "F.Mask" "F.Paste")
			(net "USB_HUB2_TI_OVERCUR1")
		)
	)
	(footprint ""
		(layer "F.Cu")
		(at 217.881962 -68.340478)
		(property "Reference" "PR3963"
			(at 0 0 0)
			(layer "F.SilkS")
			(hide yes)
			(effects
				(font
					(size 1.27 1.27)
				)
			)
		)
		(property "Value" ""
			(at 0 0 0)
			(layer "F.Fab")
			(effects
				(font
					(size 1.27 1.27)
				)
			)
		)
		(duplicate_pad_numbers_are_jumpers no)
		(fp_line
			(start -0.7874 -0.4064)
			(end 0.7874 -0.4064)
			(stroke
				(width 0.1524)
				(type default)
			)
			(layer "F.SilkS")
		)
		(fp_line
			(start -0.7874 0.4064)
			(end -0.7874 -0.4064)
			(stroke
				(width 0.1524)
				(type default)
			)
			(layer "F.SilkS")
		)
		(fp_line
			(start 0.7874 -0.4064)
			(end 0.7874 0.4064)
			(stroke
				(width 0.1524)
				(type default)
			)
			(layer "F.SilkS")
		)
		(fp_line
			(start 0.7874 0.4064)
			(end -0.7874 0.4064)
			(stroke
				(width 0.1524)
				(type default)
			)
			(layer "F.SilkS")
		)
		(fp_line
			(start -0.67945 -0.305054)
			(end -0.12065 -0.305054)
			(stroke
				(width 0.1)
				(type default)
			)
			(layer "F.Fab")
		)
		(fp_line
			(start -0.67945 0.3048)
			(end -0.67945 -0.305054)
			(stroke
				(width 0.1)
				(type default)
			)
			(layer "F.Fab")
		)
		(fp_line
			(start -0.12065 -0.305054)
			(end -0.12065 -0.2794)
			(stroke
				(width 0.1)
				(type default)
			)
			(layer "F.Fab")
		)
		(fp_line
			(start -0.12065 -0.2794)
			(end 0.12065 -0.2794)
			(stroke
				(width 0.1)
				(type default)
			)
			(layer "F.Fab")
		)
		(fp_line
			(start -0.12065 0.2794)
			(end -0.12065 0.3048)
			(stroke
				(width 0.1)
				(type default)
			)
			(layer "F.Fab")
		)
		(fp_line
			(start -0.12065 0.3048)
			(end -0.67945 0.3048)
			(stroke
				(width 0.1)
				(type default)
			)
			(layer "F.Fab")
		)
		(fp_line
			(start 0.120396 0.2794)
			(end -0.12065 0.2794)
			(stroke
				(width 0.1)
				(type default)
			)
			(layer "F.Fab")
		)
		(fp_line
			(start 0.120396 0.3048)
			(end 0.120396 0.2794)
			(stroke
				(width 0.1)
				(type default)
			)
			(layer "F.Fab")
		)
		(fp_line
			(start 0.12065 -0.3048)
			(end 0.67945 -0.3048)
			(stroke
				(width 0.1)
				(type default)
			)
			(layer "F.Fab")
		)
		(fp_line
			(start 0.12065 -0.2794)
			(end 0.12065 -0.3048)
			(stroke
				(width 0.1)
				(type default)
			)
			(layer "F.Fab")
		)
		(fp_line
			(start 0.67945 -0.3048)
			(end 0.67945 0.3048)
			(stroke
				(width 0.1)
				(type default)
			)
			(layer "F.Fab")
		)
		(fp_line
			(start 0.67945 0.3048)
			(end 0.120396 0.3048)
			(stroke
				(width 0.1)
				(type default)
			)
			(layer "F.Fab")
		)
		(pad "1" smd circle
			(at -0.40005 0)
			(size 0 0)
			(layers "F.Cu" "F.Mask" "F.Paste")
			(net "P3V3_AUX")
		)
		(pad "2" smd circle
			(at 0.40005 0)
			(size 0 0)
			(layers "F.Cu" "F.Mask" "F.Paste")
			(net "P3V3_E1S_UV_0")
		)
	)
	(footprint ""
		(layer "F.Cu")
		(at 90.833702 -370.57203 -90)
		(property "Reference" "C723"
			(at 0 0 270)
			(layer "F.SilkS")
			(hide yes)
			(effects
				(font
					(size 1.27 1.27)
				)
			)
		)
		(property "Value" ""
			(at 0 0 270)
			(layer "F.Fab")
			(effects
				(font
					(size 1.27 1.27)
				)
			)
		)
		(duplicate_pad_numbers_are_jumpers no)
		(fp_line
			(start -0.299974 0.150114)
			(end -0.299974 -0.150114)
			(stroke
				(width 0.1)
				(type default)
			)
			(layer "F.Fab")
		)
		(fp_line
			(start 0.299974 0.150114)
			(end -0.299974 0.150114)
			(stroke
				(width 0.1)
				(type default)
			)
			(layer "F.Fab")
		)
		(fp_line
			(start -0.299974 -0.150114)
			(end 0.299974 -0.150114)
			(stroke
				(width 0.1)
				(type default)
			)
			(layer "F.Fab")
		)
		(fp_line
			(start 0.299974 -0.150114)
			(end 0.299974 0.150114)
			(stroke
				(width 0.1)
				(type default)
			)
			(layer "F.Fab")
		)
		(pad "1" smd rect
			(at -0.2667 0 270)
			(size 0.3048 0.381)
			(layers "F.Cu" "F.Mask" "F.Paste")
			(net "P5E_CPU1_P1_TX_C_DP<9>")
		)
		(pad "2" smd rect
			(at 0.2667 0 270)
			(size 0.3048 0.381)
			(layers "F.Cu" "F.Mask" "F.Paste")
			(net "P5E_CPU1_P1_TX_DP<9>")
		)
	)
)
